# S9S_MB_2U (Grand Teton) — schematic netlist excerpt (pin names and nets, part order shuffled) for the footprints in the layout excerpt that follows; sources: Cadence DE-HDL packaged netlist, KiCad conversion of 03242023_DA0F0TMBIJ0_F0T_Motherboard_J_brd_V01_OCP.brd

R3659  Q_RES  10K 1% EMPTY  pkg 0402LF  page 152 : A = P3V3_AUX ; B = USB_HUB_OVCUR4
R4150  Q_RES  33.2 1% CHIP  pkg 0402LF  page 241 : A = SMB_1_PLD_3V3AUX_SDA ; B = SMB_1_PLD_3V3AUX_SDA_R1

(kicad_pcb
	(version 20260206)
	(generator "pcbnew")
	(generator_version "10.0")
	(general
		(thickness 1.6)
		(legacy_teardrops no)
	)
	(paper "A4")
	(title_block
		(title "03242023_DA0F0TMBIJ0_F0T_Motherboard_J_brd_V01_OCP.brd")
		(comment 1 "Grand Teton / footprints 1661-1662 of 6105")
	)
	(layers
		(0 "F.Cu" signal "TOP")
		(4 "In1.Cu" signal "GND")
		(6 "In2.Cu" signal "IN1")
		(8 "In3.Cu" signal "GND1")
		(10 "In4.Cu" signal "IN2")
		(12 "In5.Cu" signal "GND2")
		(14 "In6.Cu" signal "IN3")
		(16 "In7.Cu" signal "GND3")
		(18 "In8.Cu" signal "VCC")
		(20 "In9.Cu" signal "VCC1")
		(22 "In10.Cu" signal "GND4")
		(24 "In11.Cu" signal "IN4")
		(26 "In12.Cu" signal "GND5")
		(28 "In13.Cu" signal "IN5")
		(30 "In14.Cu" signal "GND6")
		(32 "In15.Cu" signal "IN6")
		(34 "In16.Cu" signal "GND7")
		(2 "B.Cu" signal "BOTTOM")
		(9 "F.Adhes" user "F.Adhesive")
		(11 "B.Adhes" user "B.Adhesive")
		(13 "F.Paste" user "Package Geometry/Pastemask Top")
		(15 "B.Paste" user "Package Geometry/Pastemask Bottom")
		(5 "F.SilkS" user "Ref Des/Silkscreen Top")
		(7 "B.SilkS" user "Ref Des/Silkscreen Bottom")
		(1 "F.Mask" user "Board Geometry/Soldermask Top")
		(3 "B.Mask" user "Board Geometry/Soldermask Bottom")
		(17 "Dwgs.User" user "User.Drawings")
		(19 "Cmts.User" user "User.Comments")
		(21 "Eco1.User" user "User.Eco1")
		(23 "Eco2.User" user "User.Eco2")
		(25 "Edge.Cuts" user "Board Geometry/Outline")
		(27 "Margin" user)
		(31 "F.CrtYd" user "Package Geometry/Place Bound Top")
		(29 "B.CrtYd" user "Package Geometry/Place Bound Bottom")
		(35 "F.Fab" user "Ref Des/Assembly Top")
		(33 "B.Fab" user "Ref Des/Assembly Bottom")
	)
	(footprint ""
		(layer "F.Cu")
		(at 160.760918 -23.398226 180)
		(property "Reference" "R4150"
			(at 0 0 180)
			(layer "F.SilkS")
			(hide yes)
			(effects
				(font
					(size 1.27 1.27)
				)
			)
		)
		(property "Value" ""
			(at 0 0 180)
			(layer "F.Fab")
			(effects
				(font
					(size 1.27 1.27)
				)
			)
		)
		(duplicate_pad_numbers_are_jumpers no)
		(fp_line
			(start 0.7874 0.4064)
			(end -0.7874 0.4064)
			(stroke
				(width 0.1524)
				(type default)
			)
			(layer "F.SilkS")
		)
		(fp_line
			(start 0.7874 -0.4064)
			(end 0.7874 0.4064)
			(stroke
				(width 0.1524)
				(type default)
			)
			(layer "F.SilkS")
		)
		(fp_line
			(start -0.7874 0.4064)
			(end -0.7874 -0.4064)
			(stroke
				(width 0.1524)
				(type default)
			)
			(layer "F.SilkS")
		)
		(fp_line
			(start -0.7874 -0.4064)
			(end 0.7874 -0.4064)
			(stroke
				(width 0.1524)
				(type default)
			)
			(layer "F.SilkS")
		)
		(fp_line
			(start 0.67945 0.3048)
			(end 0.120396 0.3048)
			(stroke
				(width 0.1)
				(type default)
			)
			(layer "F.Fab")
		)
		(fp_line
			(start 0.67945 -0.3048)
			(end 0.67945 0.3048)
			(stroke
				(width 0.1)
				(type default)
			)
			(layer "F.Fab")
		)
		(fp_line
			(start 0.12065 -0.2794)
			(end 0.12065 -0.3048)
			(stroke
				(width 0.1)
				(type default)
			)
			(layer "F.Fab")
		)
		(fp_line
			(start 0.12065 -0.3048)
			(end 0.67945 -0.3048)
			(stroke
				(width 0.1)
				(type default)
			)
			(layer "F.Fab")
		)
		(fp_line
			(start 0.120396 0.3048)
			(end 0.120396 0.2794)
			(stroke
				(width 0.1)
				(type default)
			)
			(layer "F.Fab")
		)
		(fp_line
			(start 0.120396 0.2794)
			(end -0.12065 0.2794)
			(stroke
				(width 0.1)
				(type default)
			)
			(layer "F.Fab")
		)
		(fp_line
			(start -0.12065 0.3048)
			(end -0.67945 0.3048)
			(stroke
				(width 0.1)
				(type default)
			)
			(layer "F.Fab")
		)
		(fp_line
			(start -0.12065 0.2794)
			(end -0.12065 0.3048)
			(stroke
				(width 0.1)
				(type default)
			)
			(layer "F.Fab")
		)
		(fp_line
			(start -0.12065 -0.2794)
			(end 0.12065 -0.2794)
			(stroke
				(width 0.1)
				(type default)
			)
			(layer "F.Fab")
		)
		(fp_line
			(start -0.12065 -0.305054)
			(end -0.12065 -0.2794)
			(stroke
				(width 0.1)
				(type default)
			)
			(layer "F.Fab")
		)
		(fp_line
			(start -0.67945 0.3048)
			(end -0.67945 -0.305054)
			(stroke
				(width 0.1)
				(type default)
			)
			(layer "F.Fab")
		)
		(fp_line
			(start -0.67945 -0.305054)
			(end -0.12065 -0.305054)
			(stroke
				(width 0.1)
				(type default)
			)
			(layer "F.Fab")
		)
		(pad "1" smd circle
			(at -0.40005 0 180)
			(size 0 0)
			(layers "F.Cu" "F.Mask" "F.Paste")
			(net "SMB_1_PLD_3V3AUX_SDA")
		)
		(pad "2" smd circle
			(at 0.40005 0 180)
			(size 0 0)
			(layers "F.Cu" "F.Mask" "F.Paste")
			(net "SMB_1_PLD_3V3AUX_SDA_R1")
		)
	)
	(footprint ""
		(layer "F.Cu")
		(at 15.067788 -92.687648 90)
		(property "Reference" "R3659"
			(at 0 0 90)
			(layer "F.SilkS")
			(hide yes)
			(effects
				(font
					(size 1.27 1.27)
				)
			)
		)
		(property "Value" ""
			(at 0 0 90)
			(layer "F.Fab")
			(effects
				(font
					(size 1.27 1.27)
				)
			)
		)
		(duplicate_pad_numbers_are_jumpers no)
		(fp_line
			(start 0.7874 -0.4064)
			(end 0.7874 0.4064)
			(stroke
				(width 0.1524)
				(type default)
			)
			(layer "F.SilkS")
		)
		(fp_line
			(start -0.7874 -0.4064)
			(end 0.7874 -0.4064)
			(stroke
				(width 0.1524)
				(type default)
			)
			(layer "F.SilkS")
		)
		(fp_line
			(start 0.7874 0.4064)
			(end -0.7874 0.4064)
			(stroke
				(width 0.1524)
				(type default)
			)
			(layer "F.SilkS")
		)
		(fp_line
			(start -0.7874 0.4064)
			(end -0.7874 -0.4064)
			(stroke
				(width 0.1524)
				(type default)
			)
			(layer "F.SilkS")
		)
		(fp_line
			(start -0.12065 -0.305054)
			(end -0.12065 -0.2794)
			(stroke
				(width 0.1)
				(type default)
			)
			(layer "F.Fab")
		)
		(fp_line
			(start -0.67945 -0.305054)
			(end -0.12065 -0.305054)
			(stroke
				(width 0.1)
				(type default)
			)
			(layer "F.Fab")
		)
		(fp_line
			(start 0.67945 -0.3048)
			(end 0.67945 0.3048)
			(stroke
				(width 0.1)
				(type default)
			)
			(layer "F.Fab")
		)
		(fp_line
			(start 0.12065 -0.3048)
			(end 0.67945 -0.3048)
			(stroke
				(width 0.1)
				(type default)
			)
			(layer "F.Fab")
		)
		(fp_line
			(start 0.12065 -0.2794)
			(end 0.12065 -0.3048)
			(stroke
				(width 0.1)
				(type default)
			)
			(layer "F.Fab")
		)
		(fp_line
			(start -0.12065 -0.2794)
			(end 0.12065 -0.2794)
			(stroke
				(width 0.1)
				(type default)
			)
			(layer "F.Fab")
		)
		(fp_line
			(start 0.120396 0.2794)
			(end -0.12065 0.2794)
			(stroke
				(width 0.1)
				(type default)
			)
			(layer "F.Fab")
		)
		(fp_line
			(start -0.12065 0.2794)
			(end -0.12065 0.3048)
			(stroke
				(width 0.1)
				(type default)
			)
			(layer "F.Fab")
		)
		(fp_line
			(start 0.67945 0.3048)
			(end 0.120396 0.3048)
			(stroke
				(width 0.1)
				(type default)
			)
			(layer "F.Fab")
		)
		(fp_line
			(start 0.120396 0.3048)
			(end 0.120396 0.2794)
			(stroke
				(width 0.1)
				(type default)
			)
			(layer "F.Fab")
		)
		(fp_line
			(start -0.12065 0.3048)
			(end -0.67945 0.3048)
			(stroke
				(width 0.1)
				(type default)
			)
			(layer "F.Fab")
		)
		(fp_line
			(start -0.67945 0.3048)
			(end -0.67945 -0.305054)
			(stroke
				(width 0.1)
				(type default)
			)
			(layer "F.Fab")
		)
		(pad "1" smd circle
			(at -0.40005 0 90)
			(size 0 0)
			(layers "F.Cu" "F.Mask" "F.Paste")
			(net "P3V3_AUX")
		)
		(pad "2" smd circle
			(at 0.40005 0 90)
			(size 0 0)
			(layers "F.Cu" "F.Mask" "F.Paste")
			(net "USB_HUB_OVCUR4")
		)
	)
)
